# Timingcard_PROJECT_BOMv7.xlsx — Timingcard_PROJECT_BOMv7 (bom)
| Line # | DNP | Name | Description | Designator | Revision ID | Revision State | Revision Status | Quantity | Manufacturer 1 | Manufacturer Part Number 1 | Manufacturer Lifecycle 1 | Supplier 1 | Supplier Part Number 1 | Supplier Unit Price 1 | Supplier Subtotal 1 |
|  |  | AT24MAC402-STUM-T | IC EEPROM 2K I2C 1MHZ SOT23-5 | U7 | CMP-06313-000011-1 | New From Design | Up to date | 1 | Microchip | AT24MAC402-STUM-T | Unknown | Digi-Key | AT24MAC402-STUM-TCT-ND | 0.42 | 0.42 |
|  |  | LTST-C191TBKT | LED BLUE CLEAR CHIP SMD | D3, D9, D10, D11 | CMP-22017-000008-1 | New From Design | Up to date | 4 | Vishay Lite-On | LTST-C191TBKT | Volume Production | Digi-Key | 160-1647-1-ND | 0.33 | 1.32 |
|  |  | STPS5L60S | DIODE SCHOTTKY 60V 5A SMC | D12, D19 | CMP-12187-000009-2 | New From Design | Up to date | 2 | STMicroelectronics | STPS5L60S | Volume Production | Digi-Key | 497-8487-1-ND | 0.97 | 1.94 |
|  |  | TMK212BBJ106KG-T | None | C34, C35, C58, C60 | CMP-14477-000079-2 | New From Design | Out of date | 4 | Taiyo Yuden | TMK212BBJ106KG-T | Volume Production | Digi-Key | 587-2985-1-ND | 0.18 | 0.72 |
|  | DNP | BME280 | SENSOR PRESSURE HUMIDITY TEMP | U14 | CMP-2000-05073-3 | New From Design | Up to date | 1 |  |  |  |  |  |  |  |
|  | DNP | BMX160 | IMU ACCEL/GYRO/MAG | U13 | CMP-191067-000010-1 | New From Design | Out of date | 1 |  |  |  |  |  |  |  |
|  |  | 39-30-1060 | CONN, HDR, 2X3, R/A, 4.2MM, TH, MINI-FIT JR | J38 |  | Not managed |  | 1 | Molex | 105314-1206 | Volume Production | Digi-Key | WM14977-ND | 2.27 | 2.27 |
|  |  | 155124M173200 | LED (Multiple) | D13, D14, D15, D16, D17, D18 |  | Not managed |  | 6 | Wurth Electronics | 155124M173200 | Unknown | Digi-Key | 732-11414-1-ND | 0.53 | 3.18 |
|  |  | AUX Sensor | Header, 4-Pin | P1 |  | Not managed |  | 1 | Molex | 87937-0406 | Unknown | Digi-Key | WM20573-ND | 0.49 | 0.49 |
|  |  | BAT54SW | DIO, SCHOTTKY, BAT54S, DUAL SERIES, 30V, 200MA, SC-70 | D5, D6, D7, D8 |  | Not managed |  | 4 | Diodes | BAT54SWQ-7-F | Volume Production | Digi-Key | BAT54SWQ-7-FDICT-ND | 0.35 | 1.4 |
|  |  | CAP_0402_0.1UF_50V | CAP, CER, 0.1UF, 50V, 10%, X7R, AEC-Q200, 0402 | C44, C45, C46, C47, C48, C49, C50, C51, C52, C53 |  | Not managed |  | 10 | TDK | CGA2B3X7R1H104K050BB | Volume Production | Digi-Key | 445-6899-1-ND | 0.10299999999999999 | 1.03 |
|  |  | CAP_0603_0.01UF_50V | CAP, CER, 0.01UF, 50V, 10%, X7R, 0603 | C3, C4 |  | Not managed |  | 2 | KEMET | C0603C103K5RACTU | Volume Production | Digi-Key | 399-1091-1-ND |  |  |
|  |  | CAP_0805_10UF_25V | CAP, CER, 10.UF, 25V, 10%, X5R, 0805 | C1, C5, C6, C7, C8, C13, C14, C62 |  | Not managed |  | 8 | Taiyo Yuden | TMK212BBJ106KG-T | Volume Production | Mouser | 963-TMK212BBJ106KG-T | 8.1000000000000003E-2 | 0.81 |
|  |  | CRCW080533R0FKEA | RES, 33 OHM, 1%, 1/8W, TF, 0805 | R18, R19, R20, R21 |  | Not managed |  | 4 | Vishay | CRCW080533R0FKEA | Volume Production | Digi-Key | 541-33.0CCT-ND | 0.1 | 0.4 |
|  |  | ERJ-2GE0R00X | RES, 0. OHM, 1%, 1/16W, TF, AEC-Q200, 0402 | R23, R24 |  | Not managed |  | 2 | Panasonic | ERJ-2GE0R00X | Volume Production | Digi-Key | P0.0JCT-ND | 0.1 | 0.2 |
|  |  | ERJ-3EKF1002V | RES, 10K, 1%, 1/10W, TF, 0603 | R6, R7 |  | Not managed |  | 2 | Panasonic | ERJ-3EKF1002V | Volume Production | Digi-Key | P10.0KHCT-ND | 0.1 | 0.2 |
|  |  | ERJ-3EKF2000V | RES, 200 OHM, 1%, 1/10W, TF, 0603 | R1 |  | Not managed |  | 1 | Panasonic | ERJ-3EKF2000V | Volume Production | Digi-Key | P200HCT-ND |  |  |
|  |  | ERJ-3EKF2201V | RES, 2.2K, 1%, 1/10W, TF, 0603 | R8, R9 |  | Not managed |  | 2 | Panasonic | ERJ-3EKF2201V | Volume Production | Digi-Key | P2.20KHCT-ND | 0.1 | 0.2 |
|  |  | ERJ-3EKF2612V | RES, 26.1K, 1%, 1/10W, TF, 0603 | R5 |  | Not managed |  | 1 | Panasonic | ERJ-3EKF2612V | Volume Production | Digi-Key | P26.1KHCT-ND | 0.1 | 0.1 |
|  |  | ERJ-3EKF4701V | RES, 4.7K, 1%, 1/10W, TF, 0603 | R22 |  | Not managed |  | 1 | Panasonic | ERJ-3EKF4701V | Volume Production | Digi-Key | P4.70KHCT-ND | 0.1 | 0.1 |
|  |  | ERJ-3EKF4702V | RES, 47K, 1%, 1/10W, TF, 0603 | R2, R3, R4 |  | Not managed |  | 3 | Panasonic | ERJ-3EKF4702V | Unknown | Digi-Key | P47.0KHCT-ND |  |  |
|  |  | FUSE_0603_2.00A | FUSE SLOW 2.00A 32V M 0603 | F1 |  | Not managed |  | 1 | Bourns | SF-0603S200-2 | Volume Production | Digi-Key | SF-0603S200-2CT-ND | 0.71 | 0.71 |
|  |  | GNSS Header | 8-pin GNSS header | J6, J13 |  | Not managed |  | 2 | Samtec | SQW-104-01-F-D-VS | Volume Production | Digi-Key | SAM11876-ND | 2.59 | 5.18 |
|  |  | GNSS Standoff |  | J5, J7, J8, J9, J10, J11, J12, J14 |  | Not managed |  | 8 | Keystone Electronics | 24393 | Volume Production | Digi-Key | 36-24393-ND | 0.75 | 6 |
|  |  | IS32FL3207 |  | U6 |  | Not managed |  | 1 | ISSI | IS32FL3207-QWLA3-TR | Unknown | Digi-Key | 2521-IS32FL3207-QWLA3-TRCT-ND | 2.35 | 2.35 |
|  |  | M3 screw |  | J15, J16, J17, J18, J19, J20, J21, J22, J23, J24, J25, J26, J27, J28, J29, J30, J32, J33 |  | Not managed |  | 18 | APM Hexseal | RM3X6MM2701 | Volume Production | Digi-Key | 335-1156-ND | 0.45400000000000001 | 8.17 |
|  |  | MP1482DS-LF | IC, DC/DC, MP1482DS, >4.75VIN, 0.923-15V OUT, SOIC8 | U1, U2 |  | Not managed |  | 2 | Monolithic Power Systems | MP1482DS-LF-Z | Unknown | Digi-Key | 1589-1524-1-ND | 3.1 | 6.2 |
|  |  | NC7WV125K8X | Integrated Circuit | U8, U11, U12, U16 |  | Not managed |  | 4 | ON Semiconductor / Fairchild | NC7WV125K8X | Volume Production | Digi-Key | NC7WV125K8XCT-ND | 0.8 | 3.2 |
|  |  | PM124SH-100M-RC | IND, PWR, 10.uH, 20%, 4A, 0.04DCR, 12.5X12.5MM, SHLD | L1, L2 |  | Not managed |  | 2 | Bourns JW Miller | PM124SH-100M-RC | Volume Production | Digi-Key | PM124SH-100M-RCCT-ND | 1.18 | 2.36 |
|  |  | RED | LED, RED, SML-LX0603, 635NM, 2V, 20MA, 0603 | D4 |  | Not managed |  | 1 | Lumex | SML-LX0603IW-TR | Volume Production | Digi-Key | 67-1548-1-ND | 0.33 | 0.33 |
|  |  | SA53_Header |  | J31 |  | Not managed |  | 1 | Molex | 0529910208+ | Unknown | Digi-Key | WM24007CT-ND | 1.46 | 1.46 |
|  |  | Single FPGA Conn |  | J34, J35, J36, J37 |  | Not managed |  | 4 | Panasonic | AXK680347YG | Volume Production | Digi-Key | 255-3246-1-ND | 3.13 | 12.52 |
|  |  | HTST-105-01-L-DV-A | CONN, HDR, 2X5, VERT, 0.1IN  SHROUDED, SMT, HTSH SERIES | U5 |  | Not managed |  | 1 | Samtec | HTST-105-01-L-DV-A | Volume Production | Digi-Key | SAM8809-ND | 4.42 | 4.42 |
|  | DNP | EXT GPIO | Header, 6-Pin, Dual row | P3 |  | Not managed |  | 1 |  |  |  |  |  |  |  |
|  | DNP | MAC-SA5X | MOD, MAC, MAC-SA5X, ATOMIC CLOCK | U10 |  | Not managed |  | 1 |  |  |  |  |  |  |  |
|  | DNP | PCIex4 | PCIE x4 Edge Connector,OrCAD Symbol,NC | P2 |  | Not managed |  | 1 |  |  |  |  |  |  |  |
|  | DNP | RCB-F9T | MOD, GPS | U9 |  | Not managed |  | 1 | u-blox | RCB-F9T | Unknown | Digi-Key | 672-RCB-F9T-ND | 247.5 | 247.5 |
|  | DNP | RCB-F9T-1 | MOD, GPS | U15 |  | Not managed |  | 1 | u-blox | RCB-F9T | Unknown | Digi-Key | 672-RCB-F9T-ND | 247.5 | 247.5 |
|  |  | 901-143-6RFX | Coaxial connector, 50 Ohm, -65 to 165 degC, 5-Pin THD, RoHS, Bulk | AN1, AN2, AN3, AN4 | CMP-2000-05705-1 | Released | Up to date | 4 | Amphenol RF | 901-143-6RFX | Volume Production |  |  |  |  |
|  |  | 1909763-1 | Ultra Miniature Coaxial Connector Jack, 60 V, 50 Ohm, -40 to 90 degC, RoHS, Tape and Reel | J1, J2, J3, J4 | CMP-2000-07505-1 | Released | Out of date | 4 | TE Connectivity AMP | 1909763-1 | Volume Production | Digi-Key | A118077CT-ND | 0.6 | 2.4 |
|  |  | 8240136 | TVS Diode WE-TVS-HS, VRWM=3.3V | D1, D2 | CMP-1486-00002-1 | Released | Up to date | 2 | Wurth Electronics | 8240136 | Volume Production | Digi-Key | 732-4472-1-ND | 1.28 | 2.56 |
|  |  | C0603C105K3PACTU | CAP CER 1UF 25V X5R 0603 | C38 | CMP-2006-02216-3 | Released | Up to date | 1 | KEMET | C0603C105K3PACTU | Volume Production | Digi-Key | 399-C0603C105K3PAC7867CT-ND | 0.18 | 0.18 |
|  |  | C0603X104K5RACAUTO |  | C2, C9, C10, C11, C12, C15, C16, C17, C18, C19, C21, C23, C24, C25, C26, C27, C28, C29, C30, C31, C32, C33, C36, C37, C39, C40, C59, C61, C63 | CMP-2006-00003-1 | Released | Out of date | 29 | KEMET | C0603X104K5RACAUTO | Volume Production | Digi-Key | 399-6912-1-ND | 0.13300000000000001 | 3.86 |
|  |  | CRCW0603110RFKEA |  | R12 | CMP-2000-03854-1 | Released | Up to date | 1 | Vishay | CRCW0603110RFKEA | Volume Production |  |  |  |  |
|  |  | CRCW12060000Z0EAHP |  | R45 | CMP-2003-04873-1 | Released | Up to date | 1 | Vishay Dale | CRCW12060000Z0EAHP | Volume Production | Digi-Key | 541-0.0UBCT-ND | 0.37 | 0.37 |
|  |  | DS90LV027AQMA | Automotive LVDS Dual Differential Driver, 8-pin Narrow SOIC | U3 | CMP-0058-01000-2 | Released | Up to date | 1 |  |  |  |  |  |  |  |
|  |  | DS90LV028AQMA | Automotive LVDS Dual Differential Line Receiver, 8-pin Narrow SOIC | U4 | CMP-0058-01010-2 | Released | Up to date | 1 |  |  |  |  |  |  |  |
|  |  | ERJ-3EKF2000V |  | R35, R36, R38, R39 | CMP-2000-00316-1 | Released | Out of date | 4 | Panasonic | ERJ-3EKF2000V | Volume Production |  |  |  |  |
|  |  | ERJ-3EKF4701V | Precision Thick Film Chip Resistor, 4.7 KOhm, +/- 1%, -55 to 155 degC, 0603 (1608 Metric), RoHS, Tape and Reel | R14, R15, R16, R17, R26, R27, R29, R30, R31, R32, R41 | CMP-1012-00586-3 | Released | Up to date | 11 | Yageo | RC0603FR-074K7L | Volume Production | Digi-Key | 311-4.70KHRCT-ND | 2.1000000000000001E-2 | 0.23100000000000001 |
|  |  | GCM188R71H333KA55D |  | C20, C22 | CMP-2006-02385-1 | Released | Up to date | 2 | Murata | GCM188R71H333KA55D | Unknown | Digi-Key | 490-8025-1-ND | 0.25 | 0.5 |
|  |  | RC0603FR-074K7L | Chip Resistor, 4.7 KOhm, +/- 1%, 0.1 W, -55 to 155 degC, 0603 (1608 Metric), RoHS, Tape and Reel | R10, R11 | CMP-2000-06942-1 | Released | Up to date | 2 | Yageo | RC0603FR-074K7L | Volume Production | Digi-Key | 311-4.70KHRCT-ND | 0.1 | 0.2 |
|  |  | RC0603FR-0749R9L | General Purpose Chip Resistor, 49.9 Ohm, +/- 1%, -55 to 155 degC, 0603 (1608 Metric), RoHS, Tape and Reel | R13, R25, R28, R33, R34 | CMP-1659-00036-1 | Released | Up to date | 5 | Yageo | RC0603FR-0749R9L | Volume Production | Digi-Key | 311-49.9HRCT-ND | 2.1000000000000001E-2 | 0.21 |
|  |  | RC0603FR-07100KL | RES SMD 100K OHM 1% 1/10W 0603 | R40 | CMP-2100-03662-2 | Released | Up to date | 1 | Yageo | RC0603FR-07100KL | Volume Production | Digi-Key | 311-100KHRCT-ND | 0.1 | 0.1 |
|  |  | RMCF0603FT10K0 | Chip Resistor, 10 KOhm, +/- 1%, 0.1 W, -55 to 155 degC, 0603 (1608 Metric), RoHS, Tape and Reel | R37 | CMP-2000-06990-1 | Released | Out of date | 1 | Stackpole Electronics | RMCF0603FT10K0 | Volume Production | Digi-Key | RMCF0603FT10K0CT-ND | 0.1 | 0.1 |
